(kicad_pcb
	(version 20260206)
	(generator "pcbnew")
	(generator_version "10.0")
	(general
		(thickness 1.6)
		(legacy_teardrops no)
	)
	(paper "A4")
	(title_block
		(title "04192023_DAF0TMB3IC0_F0TG_MB_C_brd_V02_OCP.brd")
		(comment 1 "Grand Teton / footprint 3955 of 8354 (U25), pads 4339-4448 of 6102")
	)
	(layers
		(0 "F.Cu" signal "TOP")
		(4 "In1.Cu" signal "GND")
		(6 "In2.Cu" signal "IN1")
		(8 "In3.Cu" signal "GND1")
		(10 "In4.Cu" signal "IN2")
		(12 "In5.Cu" signal "GND2")
		(14 "In6.Cu" signal "IN3")
		(16 "In7.Cu" signal "GND3")
		(18 "In8.Cu" signal "VCC")
		(20 "In9.Cu" signal "VCC1")
		(22 "In10.Cu" signal "GND4")
		(24 "In11.Cu" signal "IN4")
		(26 "In12.Cu" signal "GND5")
		(28 "In13.Cu" signal "IN5")
		(30 "In14.Cu" signal "GND6")
		(32 "In15.Cu" signal "IN6")
		(34 "In16.Cu" signal "GND7")
		(2 "B.Cu" signal "BOTTOM")
		(9 "F.Adhes" user "F.Adhesive")
		(11 "B.Adhes" user "B.Adhesive")
		(13 "F.Paste" user "Package Geometry/Pastemask Top")
		(15 "B.Paste" user "Package Geometry/Pastemask Bottom")
		(5 "F.SilkS" user "Ref Des/Silkscreen Top")
		(7 "B.SilkS" user "Ref Des/Silkscreen Bottom")
		(1 "F.Mask" user "Board Geometry/Soldermask Top")
		(3 "B.Mask" user "Board Geometry/Soldermask Bottom")
		(17 "Dwgs.User" user "User.Drawings")
		(19 "Cmts.User" user "User.Comments")
		(21 "Eco1.User" user "User.Eco1")
		(23 "Eco2.User" user "User.Eco2")
		(25 "Edge.Cuts" user "Board Geometry/Outline")
		(27 "Margin" user)
		(31 "F.CrtYd" user "Package Geometry/Place Bound Top")
		(29 "B.CrtYd" user "Package Geometry/Place Bound Bottom")
		(35 "F.Fab" user "Ref Des/Assembly Top")
		(33 "B.Fab" user "Ref Des/Assembly Bottom")
	)
	(footprint ""
		(layer "F.Cu")
		(at 359.867962 -258.880102 180)
		(property "Reference" "U25"
			(at -45.78477 -62.086744 0)
			(unlocked yes)
			(layer "F.SilkS")
			(effects
				(font
					(size 0.7874 0.5842)
					(thickness 0.1524)
				)
			)
		)
		(property "Value" ""
			(at 0 0 180)
			(layer "F.Fab")
			(effects
				(font
					(size 1.27 1.27)
				)
			)
		)
		(duplicate_pad_numbers_are_jumpers no)
		(pad "DA19" smd circle
			(at -17.53997 30.329886 180)
			(size 0.450088 0.450088)
			(layers "F.Cu" "F.Mask" "F.Paste")
			(net "M_I_CPU0_SB_DQ<26>")
		)
		(pad "DA20" smd circle
			(at -16.599916 30.329886 180)
			(size 0.450088 0.450088)
			(layers "F.Cu" "F.Mask" "F.Paste")
			(net "GND")
		)
		(pad "DA21" smd circle
			(at -15.660116 30.329886 180)
			(size 0.450088 0.450088)
			(layers "F.Cu" "F.Mask" "F.Paste")
			(net "M_I_CPU0_SB_DQ<25>")
		)
		(pad "DA22" smd circle
			(at -14.720062 30.329886 180)
			(size 0.450088 0.450088)
			(layers "F.Cu" "F.Mask" "F.Paste")
			(net "GND")
		)
		(pad "DA23" smd circle
			(at -13.780008 30.329886 180)
			(size 0.450088 0.450088)
			(layers "F.Cu" "F.Mask" "F.Paste")
			(net "P5E_CPU0_P3_RX_DP<14>")
		)
		(pad "DA24" smd circle
			(at -12.839954 30.329886 180)
			(size 0.450088 0.450088)
			(layers "F.Cu" "F.Mask" "F.Paste")
			(net "P5E_CPU0_P3_RX_DN<14>")
		)
		(pad "DA25" smd circle
			(at -11.8999 30.329886 180)
			(size 0.450088 0.450088)
			(layers "F.Cu" "F.Mask" "F.Paste")
			(net "GND")
		)
		(pad "DA26" smd circle
			(at -10.9601 30.329886 180)
			(size 0.450088 0.450088)
			(layers "F.Cu" "F.Mask" "F.Paste")
			(net "P5E_CPU0_P3_RX_DP<11>")
		)
		(pad "DA27" smd circle
			(at -10.020046 30.329886 180)
			(size 0.450088 0.450088)
			(layers "F.Cu" "F.Mask" "F.Paste")
			(net "P5E_CPU0_P3_RX_DN<11>")
		)
		(pad "DA28" smd circle
			(at -9.079992 30.329886 180)
			(size 0.450088 0.450088)
			(layers "F.Cu" "F.Mask" "F.Paste")
			(net "GND")
		)
		(pad "DA29" smd circle
			(at -8.139938 30.329886 180)
			(size 0.450088 0.450088)
			(layers "F.Cu" "F.Mask" "F.Paste")
			(net "P5E_CPU0_P3_RX_DP<8>")
		)
		(pad "DA30" smd circle
			(at -7.199884 30.329886 180)
			(size 0.450088 0.450088)
			(layers "F.Cu" "F.Mask" "F.Paste")
			(net "P5E_CPU0_P3_RX_DN<8>")
		)
		(pad "DA31" smd circle
			(at -6.260084 30.329886 180)
			(size 0.450088 0.450088)
			(layers "F.Cu" "F.Mask" "F.Paste")
			(net "GND")
		)
		(pad "DA32" smd circle
			(at -5.32003 30.329886 180)
			(size 0.450088 0.450088)
			(layers "F.Cu" "F.Mask" "F.Paste")
			(net "P5E_CPU0_P3_RX_DP<5>")
		)
		(pad "DA33" smd circle
			(at -4.379976 30.329886 180)
			(size 0.450088 0.450088)
			(layers "F.Cu" "F.Mask" "F.Paste")
			(net "P5E_CPU0_P3_RX_DN<5>")
		)
		(pad "DA34" smd circle
			(at -3.439922 30.329886 180)
			(size 0.450088 0.450088)
			(layers "F.Cu" "F.Mask" "F.Paste")
			(net "GND")
		)
		(pad "DA35" smd circle
			(at -2.500122 30.329886 180)
			(size 0.450088 0.450088)
			(layers "F.Cu" "F.Mask" "F.Paste")
			(net "PVDDCR_CPU1_P0")
		)
		(pad "DA36" smd circle
			(at -1.560068 30.329886 180)
			(size 0.450088 0.450088)
			(layers "F.Cu" "F.Mask" "F.Paste")
			(net "PVDDCR_CPU1_P0")
		)
		(pad "DA40" smd circle
			(at 1.260094 30.329886 180)
			(size 0.450088 0.450088)
			(layers "F.Cu" "F.Mask" "F.Paste")
			(net "PVDDCR_CPU1_P0")
		)
		(pad "DA41" smd circle
			(at 2.199894 30.329886 180)
			(size 0.450088 0.450088)
			(layers "F.Cu" "F.Mask" "F.Paste")
			(net "PVDDCR_CPU1_P0")
		)
		(pad "DA42" smd circle
			(at 3.139948 30.329886 180)
			(size 0.450088 0.450088)
			(layers "F.Cu" "F.Mask" "F.Paste")
			(net "GND")
		)
		(pad "DA43" smd circle
			(at 4.080002 30.329886 180)
			(size 0.450088 0.450088)
			(layers "F.Cu" "F.Mask" "F.Paste")
			(net "P5E_CPU0_P1_TX_DN<10>")
		)
		(pad "DA44" smd circle
			(at 5.020056 30.329886 180)
			(size 0.450088 0.450088)
			(layers "F.Cu" "F.Mask" "F.Paste")
			(net "P5E_CPU0_P1_TX_DP<10>")
		)
		(pad "DA45" smd circle
			(at 5.96011 30.329886 180)
			(size 0.450088 0.450088)
			(layers "F.Cu" "F.Mask" "F.Paste")
			(net "GND")
		)
		(pad "DA46" smd circle
			(at 6.89991 30.329886 180)
			(size 0.450088 0.450088)
			(layers "F.Cu" "F.Mask" "F.Paste")
			(net "P5E_CPU0_P1_TX_DN<7>")
		)
		(pad "DA47" smd circle
			(at 7.839964 30.329886 180)
			(size 0.450088 0.450088)
			(layers "F.Cu" "F.Mask" "F.Paste")
			(net "P5E_CPU0_P1_TX_DP<7>")
		)
		(pad "DA48" smd circle
			(at 8.780018 30.329886 180)
			(size 0.450088 0.450088)
			(layers "F.Cu" "F.Mask" "F.Paste")
			(net "GND")
		)
		(pad "DA49" smd circle
			(at 9.720072 30.329886 180)
			(size 0.450088 0.450088)
			(layers "F.Cu" "F.Mask" "F.Paste")
			(net "P5E_CPU0_P1_TX_DN<4>")
		)
		(pad "DA50" smd circle
			(at 10.659872 30.329886 180)
			(size 0.450088 0.450088)
			(layers "F.Cu" "F.Mask" "F.Paste")
			(net "P5E_CPU0_P1_TX_DP<4>")
		)
		(pad "DA51" smd circle
			(at 11.599926 30.329886 180)
			(size 0.450088 0.450088)
			(layers "F.Cu" "F.Mask" "F.Paste")
			(net "GND")
		)
		(pad "DA52" smd circle
			(at 12.53998 30.329886 180)
			(size 0.450088 0.450088)
			(layers "F.Cu" "F.Mask" "F.Paste")
			(net "P5E_CPU0_P1_TX_DN<1>")
		)
		(pad "DA53" smd circle
			(at 13.480034 30.329886 180)
			(size 0.450088 0.450088)
			(layers "F.Cu" "F.Mask" "F.Paste")
			(net "P5E_CPU0_P1_TX_DP<1>")
		)
		(pad "DA54" smd circle
			(at 14.420088 30.329886 180)
			(size 0.450088 0.450088)
			(layers "F.Cu" "F.Mask" "F.Paste")
			(net "GND")
		)
		(pad "DA55" smd circle
			(at 15.359888 30.329886 180)
			(size 0.450088 0.450088)
			(layers "F.Cu" "F.Mask" "F.Paste")
			(net "M_C_CPU0_SB_DQ<25>")
		)
		(pad "DA56" smd circle
			(at 16.299942 30.329886 180)
			(size 0.450088 0.450088)
			(layers "F.Cu" "F.Mask" "F.Paste")
			(net "GND")
		)
		(pad "DA57" smd circle
			(at 17.239996 30.329886 180)
			(size 0.450088 0.450088)
			(layers "F.Cu" "F.Mask" "F.Paste")
			(net "M_C_CPU0_SB_DQ<26>")
		)
		(pad "DA58" smd circle
			(at 18.18005 30.329886 180)
			(size 0.450088 0.450088)
			(layers "F.Cu" "F.Mask" "F.Paste")
			(net "GND")
		)
		(pad "DA59" smd circle
			(at 19.120104 30.329886 180)
			(size 0.450088 0.450088)
			(layers "F.Cu" "F.Mask" "F.Paste")
			(net "M_D_CPU0_SB_DQ<25>")
		)
		(pad "DA60" smd circle
			(at 20.059904 30.329886 180)
			(size 0.450088 0.450088)
			(layers "F.Cu" "F.Mask" "F.Paste")
			(net "M_D_CPU0_SB_DQ<26>")
		)
		(pad "DA61" smd circle
			(at 20.999958 30.329886 180)
			(size 0.450088 0.450088)
			(layers "F.Cu" "F.Mask" "F.Paste")
			(net "GND")
		)
		(pad "DA62" smd circle
			(at 21.940012 30.329886 180)
			(size 0.450088 0.450088)
			(layers "F.Cu" "F.Mask" "F.Paste")
			(net "M_B_CPU0_SB_DQ<25>")
		)
		(pad "DA63" smd circle
			(at 22.880066 30.329886 180)
			(size 0.450088 0.450088)
			(layers "F.Cu" "F.Mask" "F.Paste")
			(net "GND")
		)
		(pad "DA64" smd circle
			(at 23.82012 30.329886 180)
			(size 0.450088 0.450088)
			(layers "F.Cu" "F.Mask" "F.Paste")
			(net "M_B_CPU0_SB_DQ<26>")
		)
		(pad "DA65" smd circle
			(at 24.75992 30.329886 180)
			(size 0.450088 0.450088)
			(layers "F.Cu" "F.Mask" "F.Paste")
			(net "GND")
		)
		(pad "DA66" smd circle
			(at 25.699974 30.329886 180)
			(size 0.450088 0.450088)
			(layers "F.Cu" "F.Mask" "F.Paste")
			(net "M_F_CPU0_SB_DQ<25>")
		)
		(pad "DA67" smd circle
			(at 26.640028 30.329886 180)
			(size 0.450088 0.450088)
			(layers "F.Cu" "F.Mask" "F.Paste")
			(net "M_F_CPU0_SB_DQ<26>")
		)
		(pad "DA68" smd circle
			(at 27.580082 30.329886 180)
			(size 0.450088 0.450088)
			(layers "F.Cu" "F.Mask" "F.Paste")
			(net "GND")
		)
		(pad "DA69" smd circle
			(at 28.519882 30.329886 180)
			(size 0.450088 0.450088)
			(layers "F.Cu" "F.Mask" "F.Paste")
			(net "M_E_CPU0_SB_DQ<25>")
		)
		(pad "DA70" smd circle
			(at 29.459936 30.329886 180)
			(size 0.450088 0.450088)
			(layers "F.Cu" "F.Mask" "F.Paste")
			(net "GND")
		)
		(pad "DA71" smd circle
			(at 30.39999 30.329886 180)
			(size 0.450088 0.450088)
			(layers "F.Cu" "F.Mask" "F.Paste")
			(net "M_E_CPU0_SB_DQ<26>")
		)
		(pad "DA72" smd circle
			(at 31.340044 30.329886 180)
			(size 0.450088 0.450088)
			(layers "F.Cu" "F.Mask" "F.Paste")
			(net "GND")
		)
		(pad "DA73" smd circle
			(at 32.280098 30.329886 180)
			(size 0.450088 0.450088)
			(layers "F.Cu" "F.Mask" "F.Paste")
			(net "M_A_CPU0_SB_DQ<25>")
		)
		(pad "DA74" smd circle
			(at 33.219898 30.329886 180)
			(size 0.450088 0.450088)
			(layers "F.Cu" "F.Mask" "F.Paste")
			(net "M_A_CPU0_SB_DQ<26>")
		)
		(pad "DA75" smd circle
			(at 34.159952 30.329886 180)
			(size 0.450088 0.450088)
			(layers "F.Cu" "F.Mask" "F.Paste")
			(net "GND")
		)
		(pad "DB2" smd circle
			(at -33.990026 31.139892 180)
			(size 0.450088 0.450088)
			(layers "F.Cu" "F.Mask" "F.Paste")
			(net "M_G_CPU0_SB_DQS_DP<3>")
		)
		(pad "DB3" smd circle
			(at -33.049972 31.139892 180)
			(size 0.450088 0.450088)
			(layers "F.Cu" "F.Mask" "F.Paste")
			(net "GND")
		)
		(pad "DB4" smd circle
			(at -32.109918 31.139892 180)
			(size 0.450088 0.450088)
			(layers "F.Cu" "F.Mask" "F.Paste")
			(net "M_G_CPU0_SB_DQ<27>")
		)
		(pad "DB5" smd circle
			(at -31.170118 31.139892 180)
			(size 0.450088 0.450088)
			(layers "F.Cu" "F.Mask" "F.Paste")
			(net "PVDD11_S3_P0")
		)
		(pad "DB6" smd circle
			(at -30.230064 31.139892 180)
			(size 0.450088 0.450088)
			(layers "F.Cu" "F.Mask" "F.Paste")
			(net "M_K_CPU0_SB_DQS_DP<3>")
		)
		(pad "DB7" smd circle
			(at -29.29001 31.139892 180)
			(size 0.450088 0.450088)
			(layers "F.Cu" "F.Mask" "F.Paste")
			(net "M_K_CPU0_SB_DQ<27>")
		)
		(pad "DB8" smd circle
			(at -28.349956 31.139892 180)
			(size 0.450088 0.450088)
			(layers "F.Cu" "F.Mask" "F.Paste")
			(net "GND")
		)
		(pad "DB9" smd circle
			(at -27.409902 31.139892 180)
			(size 0.450088 0.450088)
			(layers "F.Cu" "F.Mask" "F.Paste")
			(net "M_L_CPU0_SB_DQS_DP<3>")
		)
		(pad "DB10" smd circle
			(at -26.470102 31.139892 180)
			(size 0.450088 0.450088)
			(layers "F.Cu" "F.Mask" "F.Paste")
			(net "GND")
		)
		(pad "DB11" smd circle
			(at -25.530048 31.139892 180)
			(size 0.450088 0.450088)
			(layers "F.Cu" "F.Mask" "F.Paste")
			(net "M_L_CPU0_SB_DQ<27>")
		)
		(pad "DB12" smd circle
			(at -24.589994 31.139892 180)
			(size 0.450088 0.450088)
			(layers "F.Cu" "F.Mask" "F.Paste")
			(net "PVDD11_S3_P0")
		)
		(pad "DB13" smd circle
			(at -23.64994 31.139892 180)
			(size 0.450088 0.450088)
			(layers "F.Cu" "F.Mask" "F.Paste")
			(net "M_H_CPU0_SB_DQS_DP<3>")
		)
		(pad "DB14" smd circle
			(at -22.709886 31.139892 180)
			(size 0.450088 0.450088)
			(layers "F.Cu" "F.Mask" "F.Paste")
			(net "M_H_CPU0_SB_DQ<27>")
		)
		(pad "DB15" smd circle
			(at -21.770086 31.139892 180)
			(size 0.450088 0.450088)
			(layers "F.Cu" "F.Mask" "F.Paste")
			(net "GND")
		)
		(pad "DB16" smd circle
			(at -20.830032 31.139892 180)
			(size 0.450088 0.450088)
			(layers "F.Cu" "F.Mask" "F.Paste")
			(net "M_J_CPU0_SB_DQS_DP<3>")
		)
		(pad "DB17" smd circle
			(at -19.889978 31.139892 180)
			(size 0.450088 0.450088)
			(layers "F.Cu" "F.Mask" "F.Paste")
			(net "GND")
		)
		(pad "DB18" smd circle
			(at -18.949924 31.139892 180)
			(size 0.450088 0.450088)
			(layers "F.Cu" "F.Mask" "F.Paste")
			(net "M_J_CPU0_SB_DQ<27>")
		)
		(pad "DB19" smd circle
			(at -18.010124 31.139892 180)
			(size 0.450088 0.450088)
			(layers "F.Cu" "F.Mask" "F.Paste")
			(net "PVDD11_S3_P0")
		)
		(pad "DB20" smd circle
			(at -17.07007 31.139892 180)
			(size 0.450088 0.450088)
			(layers "F.Cu" "F.Mask" "F.Paste")
			(net "M_I_CPU0_SB_DQS_DP<3>")
		)
		(pad "DB21" smd circle
			(at -16.130016 31.139892 180)
			(size 0.450088 0.450088)
			(layers "F.Cu" "F.Mask" "F.Paste")
			(net "M_I_CPU0_SB_DQ<27>")
		)
		(pad "DB22" smd circle
			(at -15.189962 31.139892 180)
			(size 0.450088 0.450088)
			(layers "F.Cu" "F.Mask" "F.Paste")
			(net "GND")
		)
		(pad "DB23" smd circle
			(at -14.249908 31.139892 180)
			(size 0.450088 0.450088)
			(layers "F.Cu" "F.Mask" "F.Paste")
			(net "PVDDCR_CPU1_P0")
		)
		(pad "DB24" smd circle
			(at -13.310108 31.139892 180)
			(size 0.450088 0.450088)
			(layers "F.Cu" "F.Mask" "F.Paste")
			(net "PVDDCR_CPU1_P0")
		)
		(pad "DB25" smd circle
			(at -12.370054 31.139892 180)
			(size 0.450088 0.450088)
			(layers "F.Cu" "F.Mask" "F.Paste")
			(net "GND")
		)
		(pad "DB26" smd circle
			(at -11.43 31.139892 180)
			(size 0.450088 0.450088)
			(layers "F.Cu" "F.Mask" "F.Paste")
			(net "PVDDCR_CPU1_P0")
		)
		(pad "DB27" smd circle
			(at -10.489946 31.139892 180)
			(size 0.450088 0.450088)
			(layers "F.Cu" "F.Mask" "F.Paste")
			(net "PVDDCR_CPU1_P0")
		)
		(pad "DB28" smd circle
			(at -9.549892 31.139892 180)
			(size 0.450088 0.450088)
			(layers "F.Cu" "F.Mask" "F.Paste")
			(net "GND")
		)
		(pad "DB29" smd circle
			(at -8.610092 31.139892 180)
			(size 0.450088 0.450088)
			(layers "F.Cu" "F.Mask" "F.Paste")
			(net "PVDDCR_CPU1_P0")
		)
		(pad "DB30" smd circle
			(at -7.670038 31.139892 180)
			(size 0.450088 0.450088)
			(layers "F.Cu" "F.Mask" "F.Paste")
			(net "PVDDCR_CPU1_P0")
		)
		(pad "DB31" smd circle
			(at -6.729984 31.139892 180)
			(size 0.450088 0.450088)
			(layers "F.Cu" "F.Mask" "F.Paste")
			(net "GND")
		)
		(pad "DB32" smd circle
			(at -5.78993 31.139892 180)
			(size 0.450088 0.450088)
			(layers "F.Cu" "F.Mask" "F.Paste")
			(net "PVDDCR_CPU1_P0")
		)
		(pad "DB33" smd circle
			(at -4.849876 31.139892 180)
			(size 0.450088 0.450088)
			(layers "F.Cu" "F.Mask" "F.Paste")
			(net "PVDDCR_CPU1_P0")
		)
		(pad "DB34" smd circle
			(at -3.910076 31.139892 180)
			(size 0.450088 0.450088)
			(layers "F.Cu" "F.Mask" "F.Paste")
			(net "GND")
		)
		(pad "DB35" smd circle
			(at -2.970022 31.139892 180)
			(size 0.450088 0.450088)
			(layers "F.Cu" "F.Mask" "F.Paste")
			(net "P5E_CPU0_P3_RX_DP<2>")
		)
		(pad "DB36" smd circle
			(at -2.029968 31.139892 180)
			(size 0.450088 0.450088)
			(layers "F.Cu" "F.Mask" "F.Paste")
			(net "P5E_CPU0_P3_RX_DN<2>")
		)
		(pad "DB37" smd circle
			(at -1.089914 31.139892 180)
			(size 0.450088 0.450088)
			(layers "F.Cu" "F.Mask" "F.Paste")
			(net "GND")
		)
		(pad "DB39" smd circle
			(at 0.78994 31.139892 180)
			(size 0.450088 0.450088)
			(layers "F.Cu" "F.Mask" "F.Paste")
			(net "GND")
		)
		(pad "DB40" smd circle
			(at 1.729994 31.139892 180)
			(size 0.450088 0.450088)
			(layers "F.Cu" "F.Mask" "F.Paste")
			(net "P5E_CPU0_P1_TX_DN<13>")
		)
		(pad "DB41" smd circle
			(at 2.670048 31.139892 180)
			(size 0.450088 0.450088)
			(layers "F.Cu" "F.Mask" "F.Paste")
			(net "P5E_CPU0_P1_TX_DP<13>")
		)
		(pad "DB42" smd circle
			(at 3.610102 31.139892 180)
			(size 0.450088 0.450088)
			(layers "F.Cu" "F.Mask" "F.Paste")
			(net "GND")
		)
		(pad "DB43" smd circle
			(at 4.549902 31.139892 180)
			(size 0.450088 0.450088)
			(layers "F.Cu" "F.Mask" "F.Paste")
			(net "PVDDCR_CPU1_P0")
		)
		(pad "DB44" smd circle
			(at 5.489956 31.139892 180)
			(size 0.450088 0.450088)
			(layers "F.Cu" "F.Mask" "F.Paste")
			(net "PVDDCR_CPU1_P0")
		)
		(pad "DB45" smd circle
			(at 6.43001 31.139892 180)
			(size 0.450088 0.450088)
			(layers "F.Cu" "F.Mask" "F.Paste")
			(net "GND")
		)
		(pad "DB46" smd circle
			(at 7.370064 31.139892 180)
			(size 0.450088 0.450088)
			(layers "F.Cu" "F.Mask" "F.Paste")
			(net "PVDDCR_CPU1_P0")
		)
		(pad "DB47" smd circle
			(at 8.310118 31.139892 180)
			(size 0.450088 0.450088)
			(layers "F.Cu" "F.Mask" "F.Paste")
			(net "PVDDCR_CPU1_P0")
		)
		(pad "DB48" smd circle
			(at 9.249918 31.139892 180)
			(size 0.450088 0.450088)
			(layers "F.Cu" "F.Mask" "F.Paste")
			(net "GND")
		)
		(pad "DB49" smd circle
			(at 10.189972 31.139892 180)
			(size 0.450088 0.450088)
			(layers "F.Cu" "F.Mask" "F.Paste")
			(net "PVDDCR_CPU1_P0")
		)
		(pad "DB50" smd circle
			(at 11.130026 31.139892 180)
			(size 0.450088 0.450088)
			(layers "F.Cu" "F.Mask" "F.Paste")
			(net "PVDDCR_CPU1_P0")
		)
		(pad "DB51" smd circle
			(at 12.07008 31.139892 180)
			(size 0.450088 0.450088)
			(layers "F.Cu" "F.Mask" "F.Paste")
			(net "GND")
		)
		(pad "DB52" smd circle
			(at 13.00988 31.139892 180)
			(size 0.450088 0.450088)
			(layers "F.Cu" "F.Mask" "F.Paste")
			(net "PVDDCR_CPU1_P0")
		)
		(pad "DB53" smd circle
			(at 13.949934 31.139892 180)
			(size 0.450088 0.450088)
			(layers "F.Cu" "F.Mask" "F.Paste")
			(net "PVDDCR_CPU1_P0")
		)
		(pad "DB54" smd circle
			(at 14.889988 31.139892 180)
			(size 0.450088 0.450088)
			(layers "F.Cu" "F.Mask" "F.Paste")
			(net "GND")
		)
		(pad "DB55" smd circle
			(at 15.830042 31.139892 180)
			(size 0.450088 0.450088)
			(layers "F.Cu" "F.Mask" "F.Paste")
			(net "M_C_CPU0_SB_DQ<27>")
		)
		(pad "DB56" smd circle
			(at 16.770096 31.139892 180)
			(size 0.450088 0.450088)
			(layers "F.Cu" "F.Mask" "F.Paste")
			(net "M_C_CPU0_SB_DQS_DP<3>")
		)
		(pad "DB57" smd circle
			(at 17.709896 31.139892 180)
			(size 0.450088 0.450088)
			(layers "F.Cu" "F.Mask" "F.Paste")
			(net "PVDDIO_P0")
		)
		(pad "DB58" smd circle
			(at 18.64995 31.139892 180)
			(size 0.450088 0.450088)
			(layers "F.Cu" "F.Mask" "F.Paste")
			(net "M_D_CPU0_SB_DQ<27>")
		)
	)
)
